# S9S_MB_2U (Grand Teton) — schematic netlist excerpt (pin names and nets, part order shuffled) for the footprints in the layout excerpt that follows; sources: Cadence DE-HDL packaged netlist, KiCad conversion of 03242023_DA0F0TMBIJ0_F0T_Motherboard_J_brd_V01_OCP.brd

R3559  Q_RES  0 5% CHIP  pkg 0402LF  page 172 : A = OCP_V3_2_P3V3_ADC_ALERT_R ; B = OCP_V3_2_P3V3_ADC_ALERT

(kicad_pcb
	(version 20260206)
	(generator "pcbnew")
	(generator_version "10.0")
	(general
		(thickness 1.6)
		(legacy_teardrops no)
	)
	(paper "A4")
	(title_block
		(title "03242023_DA0F0TMBIJ0_F0T_Motherboard_J_brd_V01_OCP.brd")
		(comment 1 "Grand Teton / footprints 1334-1334 of 6105")
	)
	(layers
		(0 "F.Cu" signal "TOP")
		(4 "In1.Cu" signal "GND")
		(6 "In2.Cu" signal "IN1")
		(8 "In3.Cu" signal "GND1")
		(10 "In4.Cu" signal "IN2")
		(12 "In5.Cu" signal "GND2")
		(14 "In6.Cu" signal "IN3")
		(16 "In7.Cu" signal "GND3")
		(18 "In8.Cu" signal "VCC")
		(20 "In9.Cu" signal "VCC1")
		(22 "In10.Cu" signal "GND4")
		(24 "In11.Cu" signal "IN4")
		(26 "In12.Cu" signal "GND5")
		(28 "In13.Cu" signal "IN5")
		(30 "In14.Cu" signal "GND6")
		(32 "In15.Cu" signal "IN6")
		(34 "In16.Cu" signal "GND7")
		(2 "B.Cu" signal "BOTTOM")
		(9 "F.Adhes" user "F.Adhesive")
		(11 "B.Adhes" user "B.Adhesive")
		(13 "F.Paste" user "Package Geometry/Pastemask Top")
		(15 "B.Paste" user "Package Geometry/Pastemask Bottom")
		(5 "F.SilkS" user "Ref Des/Silkscreen Top")
		(7 "B.SilkS" user "Ref Des/Silkscreen Bottom")
		(1 "F.Mask" user "Board Geometry/Soldermask Top")
		(3 "B.Mask" user "Board Geometry/Soldermask Bottom")
		(17 "Dwgs.User" user "User.Drawings")
		(19 "Cmts.User" user "User.Comments")
		(21 "Eco1.User" user "User.Eco1")
		(23 "Eco2.User" user "User.Eco2")
		(25 "Edge.Cuts" user "Board Geometry/Outline")
		(27 "Margin" user)
		(31 "F.CrtYd" user "Package Geometry/Place Bound Top")
		(29 "B.CrtYd" user "Package Geometry/Place Bound Bottom")
		(35 "F.Fab" user "Ref Des/Assembly Top")
		(33 "B.Fab" user "Ref Des/Assembly Bottom")
	)
	(footprint ""
		(layer "F.Cu")
		(at 68.212462 -37.389562 180)
		(property "Reference" "R3559"
			(at 0 0 180)
			(layer "F.SilkS")
			(hide yes)
			(effects
				(font
					(size 1.27 1.27)
				)
			)
		)
		(property "Value" ""
			(at 0 0 180)
			(layer "F.Fab")
			(effects
				(font
					(size 1.27 1.27)
				)
			)
		)
		(duplicate_pad_numbers_are_jumpers no)
		(fp_line
			(start 0.7874 0.4064)
			(end -0.7874 0.4064)
			(stroke
				(width 0.1524)
				(type default)
			)
			(layer "F.SilkS")
		)
		(fp_line
			(start 0.7874 -0.4064)
			(end 0.7874 0.4064)
			(stroke
				(width 0.1524)
				(type default)
			)
			(layer "F.SilkS")
		)
		(fp_line
			(start -0.7874 0.4064)
			(end -0.7874 -0.4064)
			(stroke
				(width 0.1524)
				(type default)
			)
			(layer "F.SilkS")
		)
		(fp_line
			(start -0.7874 -0.4064)
			(end 0.7874 -0.4064)
			(stroke
				(width 0.1524)
				(type default)
			)
			(layer "F.SilkS")
		)
		(fp_line
			(start 0.67945 0.3048)
			(end 0.120396 0.3048)
			(stroke
				(width 0.1)
				(type default)
			)
			(layer "F.Fab")
		)
		(fp_line
			(start 0.67945 -0.3048)
			(end 0.67945 0.3048)
			(stroke
				(width 0.1)
				(type default)
			)
			(layer "F.Fab")
		)
		(fp_line
			(start 0.12065 -0.2794)
			(end 0.12065 -0.3048)
			(stroke
				(width 0.1)
				(type default)
			)
			(layer "F.Fab")
		)
		(fp_line
			(start 0.12065 -0.3048)
			(end 0.67945 -0.3048)
			(stroke
				(width 0.1)
				(type default)
			)
			(layer "F.Fab")
		)
		(fp_line
			(start 0.120396 0.3048)
			(end 0.120396 0.2794)
			(stroke
				(width 0.1)
				(type default)
			)
			(layer "F.Fab")
		)
		(fp_line
			(start 0.120396 0.2794)
			(end -0.12065 0.2794)
			(stroke
				(width 0.1)
				(type default)
			)
			(layer "F.Fab")
		)
		(fp_line
			(start -0.12065 0.3048)
			(end -0.67945 0.3048)
			(stroke
				(width 0.1)
				(type default)
			)
			(layer "F.Fab")
		)
		(fp_line
			(start -0.12065 0.2794)
			(end -0.12065 0.3048)
			(stroke
				(width 0.1)
				(type default)
			)
			(layer "F.Fab")
		)
		(fp_line
			(start -0.12065 -0.2794)
			(end 0.12065 -0.2794)
			(stroke
				(width 0.1)
				(type default)
			)
			(layer "F.Fab")
		)
		(fp_line
			(start -0.12065 -0.305054)
			(end -0.12065 -0.2794)
			(stroke
				(width 0.1)
				(type default)
			)
			(layer "F.Fab")
		)
		(fp_line
			(start -0.67945 0.3048)
			(end -0.67945 -0.305054)
			(stroke
				(width 0.1)
				(type default)
			)
			(layer "F.Fab")
		)
		(fp_line
			(start -0.67945 -0.305054)
			(end -0.12065 -0.305054)
			(stroke
				(width 0.1)
				(type default)
			)
			(layer "F.Fab")
		)
		(pad "1" smd circle
			(at -0.40005 0 180)
			(size 0 0)
			(layers "F.Cu" "F.Mask" "F.Paste")
			(net "OCP_V3_2_P3V3_ADC_ALERT_R")
		)
		(pad "2" smd circle
			(at 0.40005 0 180)
			(size 0 0)
			(layers "F.Cu" "F.Mask" "F.Paste")
			(net "OCP_V3_2_P3V3_ADC_ALERT")
		)
	)
)
